# T6G (Grand Teton) — schematic netlist excerpt (pin names and nets, part order shuffled) for the footprints in the layout excerpt that follows; sources: Cadence DE-HDL packaged netlist, KiCad conversion of 04192023_DAF0TMB3IC0_F0TG_MB_C_brd_V02_OCP.brd

J45  CONN60_101062636003K02LF  CONN60_10106263-6003K02LF IO  pkg HSD_M60D4H2D_P2-54W2-54_LDHXB  page 240
  A1  = TP_J45_A1
  A2  = FM_AC_PWR_BTN_PDB_N
  A3  = P3V3_PDB_AUX_ADC
  B1  = RST_SMB_SWITCH_R_N
  B2  = PWRGD_P3V3_AUX_PDB_BUF
  B3  = GND
  C1  = SMB_FAN_3V3AUX_BUF_R_SCL
  C2  = SMB_FAN_3V3AUX_BUF_R_SDA
  C3  = HPDB_HSC_PWRGD_R
  D1  = FM_FAN_PWR_EN_R
  D2  = FM_GPU_HSC_EN_BUF_R1
  D3  = PDB_PRSNT_N
  P1_1  = GND
  P1_2  = GND
  P1_3  = GND
  P1_4  = GND
  P1_5  = GND
  P1_6  = GND
  P1_7  = GND
  P1_8  = GND
  P2_1  = GND
  P2_2  = GND
  P2_3  = GND
  P2_4  = GND
  P2_5  = GND
  P2_6  = GND
  P2_7  = GND
  P2_8  = GND
  P3_1  = GND
  P3_2  = GND
  P3_3  = GND
  P3_4  = GND
  P3_5  = GND
  P3_6  = GND
  P3_7  = GND
  P3_8  = GND
  P4_1  = P12V_PSU
  P4_2  = P12V_PSU
  P4_3  = P12V_PSU
  P4_4  = P12V_PSU
  P4_5  = P12V_PSU
  P4_6  = P12V_PSU
  P4_7  = P12V_PSU
  P4_8  = P12V_PSU
  P5_1  = P12V_PSU
  P5_2  = P12V_PSU
  P5_3  = P12V_PSU
  P5_4  = P12V_PSU
  P5_5  = P12V_PSU
  P5_6  = P12V_PSU
  P5_7  = P12V_PSU
  P5_8  = P12V_PSU
  P6_1  = P12V_PSU
  P6_2  = P12V_PSU
  P6_3  = P12V_PSU
  P6_4  = P12V_PSU
  P6_5  = P12V_PSU
  P6_6  = P12V_PSU
  P6_7  = P12V_PSU
  P6_8  = P12V_PSU

(kicad_pcb
	(version 20260206)
	(generator "pcbnew")
	(generator_version "10.0")
	(general
		(thickness 1.6)
		(legacy_teardrops no)
	)
	(paper "A4")
	(title_block
		(title "04192023_DAF0TMB3IC0_F0TG_MB_C_brd_V02_OCP.brd")
		(comment 1 "Grand Teton / footprint 1872 of 8354 (J45), pads 36-62 of 62")
	)
	(layers
		(0 "F.Cu" signal "TOP")
		(4 "In1.Cu" signal "GND")
		(6 "In2.Cu" signal "IN1")
		(8 "In3.Cu" signal "GND1")
		(10 "In4.Cu" signal "IN2")
		(12 "In5.Cu" signal "GND2")
		(14 "In6.Cu" signal "IN3")
		(16 "In7.Cu" signal "GND3")
		(18 "In8.Cu" signal "VCC")
		(20 "In9.Cu" signal "VCC1")
		(22 "In10.Cu" signal "GND4")
		(24 "In11.Cu" signal "IN4")
		(26 "In12.Cu" signal "GND5")
		(28 "In13.Cu" signal "IN5")
		(30 "In14.Cu" signal "GND6")
		(32 "In15.Cu" signal "IN6")
		(34 "In16.Cu" signal "GND7")
		(2 "B.Cu" signal "BOTTOM")
		(9 "F.Adhes" user "F.Adhesive")
		(11 "B.Adhes" user "B.Adhesive")
		(13 "F.Paste" user "Package Geometry/Pastemask Top")
		(15 "B.Paste" user "Package Geometry/Pastemask Bottom")
		(5 "F.SilkS" user "Ref Des/Silkscreen Top")
		(7 "B.SilkS" user "Ref Des/Silkscreen Bottom")
		(1 "F.Mask" user "Board Geometry/Soldermask Top")
		(3 "B.Mask" user "Board Geometry/Soldermask Bottom")
		(17 "Dwgs.User" user "User.Drawings")
		(19 "Cmts.User" user "User.Comments")
		(21 "Eco1.User" user "User.Eco1")
		(23 "Eco2.User" user "User.Eco2")
		(25 "Edge.Cuts" user "Board Geometry/Outline")
		(27 "Margin" user)
		(31 "F.CrtYd" user "Package Geometry/Place Bound Top")
		(29 "B.CrtYd" user "Package Geometry/Place Bound Bottom")
		(35 "F.Fab" user "Ref Des/Assembly Top")
		(33 "B.Fab" user "Ref Des/Assembly Bottom")
	)
	(footprint ""
		(layer "F.Cu")
		(at 238.45012 -435.58206 -90)
		(property "Reference" "J45"
			(at 11.30173 -38.15588 0)
			(unlocked yes)
			(layer "F.SilkS")
			(effects
				(font
					(size 0.7874 0.5842)
					(thickness 0.1524)
				)
				(justify left)
			)
		)
		(property "Value" ""
			(at 0 0 270)
			(layer "F.Fab")
			(effects
				(font
					(size 1.27 1.27)
				)
			)
		)
		(duplicate_pad_numbers_are_jumpers no)
		(pad "P3_6" thru_hole circle
			(at 2.54 -5.08 270)
			(size 1.669796 1.669796)
			(drill 1.01981)
			(layers "*.Cu" "*.Mask")
			(remove_unused_layers no)
			(net "GND")
			(clearance -0.070866)
		)
		(pad "P3_7" thru_hole circle
			(at 5.08 -5.08 270)
			(size 1.669796 1.669796)
			(drill 1.01981)
			(layers "*.Cu" "*.Mask")
			(remove_unused_layers no)
			(net "GND")
			(clearance -0.070866)
		)
		(pad "P3_8" thru_hole circle
			(at 7.62 -5.08 270)
			(size 1.669796 1.669796)
			(drill 1.01981)
			(layers "*.Cu" "*.Mask")
			(remove_unused_layers no)
			(net "GND")
			(clearance -0.070866)
		)
		(pad "P4_1" thru_hole circle
			(at 0 10.16 270)
			(size 1.669796 1.669796)
			(drill 1.01981)
			(layers "*.Cu" "*.Mask")
			(remove_unused_layers no)
			(net "P12V_PSU")
			(clearance -0.070866)
		)
		(pad "P4_2" thru_hole circle
			(at 2.54 10.16 270)
			(size 1.669796 1.669796)
			(drill 1.01981)
			(layers "*.Cu" "*.Mask")
			(remove_unused_layers no)
			(net "P12V_PSU")
			(clearance -0.070866)
		)
		(pad "P4_3" thru_hole circle
			(at 5.08 10.16 270)
			(size 1.669796 1.669796)
			(drill 1.01981)
			(layers "*.Cu" "*.Mask")
			(remove_unused_layers no)
			(net "P12V_PSU")
			(clearance -0.070866)
		)
		(pad "P4_4" thru_hole circle
			(at 7.62 10.16 270)
			(size 1.669796 1.669796)
			(drill 1.01981)
			(layers "*.Cu" "*.Mask")
			(remove_unused_layers no)
			(net "P12V_PSU")
			(clearance -0.070866)
		)
		(pad "P4_5" thru_hole circle
			(at 0 12.7 270)
			(size 1.669796 1.669796)
			(drill 1.01981)
			(layers "*.Cu" "*.Mask")
			(remove_unused_layers no)
			(net "P12V_PSU")
			(clearance -0.070866)
		)
		(pad "P4_6" thru_hole circle
			(at 2.54 12.7 270)
			(size 1.669796 1.669796)
			(drill 1.01981)
			(layers "*.Cu" "*.Mask")
			(remove_unused_layers no)
			(net "P12V_PSU")
			(clearance -0.070866)
		)
		(pad "P4_7" thru_hole circle
			(at 5.08 12.7 270)
			(size 1.669796 1.669796)
			(drill 1.01981)
			(layers "*.Cu" "*.Mask")
			(remove_unused_layers no)
			(net "P12V_PSU")
			(clearance -0.070866)
		)
		(pad "P4_8" thru_hole circle
			(at 7.62 12.7 270)
			(size 1.669796 1.669796)
			(drill 1.01981)
			(layers "*.Cu" "*.Mask")
			(remove_unused_layers no)
			(net "P12V_PSU")
			(clearance -0.070866)
		)
		(pad "P5_1" thru_hole circle
			(at 0 19.05 270)
			(size 1.669796 1.669796)
			(drill 1.01981)
			(layers "*.Cu" "*.Mask")
			(remove_unused_layers no)
			(net "P12V_PSU")
			(clearance -0.070866)
		)
		(pad "P5_2" thru_hole circle
			(at 2.54 19.05 270)
			(size 1.669796 1.669796)
			(drill 1.01981)
			(layers "*.Cu" "*.Mask")
			(remove_unused_layers no)
			(net "P12V_PSU")
			(clearance -0.070866)
		)
		(pad "P5_3" thru_hole circle
			(at 5.08 19.05 270)
			(size 1.669796 1.669796)
			(drill 1.01981)
			(layers "*.Cu" "*.Mask")
			(remove_unused_layers no)
			(net "P12V_PSU")
			(clearance -0.070866)
		)
		(pad "P5_4" thru_hole circle
			(at 7.62 19.05 270)
			(size 1.669796 1.669796)
			(drill 1.01981)
			(layers "*.Cu" "*.Mask")
			(remove_unused_layers no)
			(net "P12V_PSU")
			(clearance -0.070866)
		)
		(pad "P5_5" thru_hole circle
			(at 0 21.59 270)
			(size 1.669796 1.669796)
			(drill 1.01981)
			(layers "*.Cu" "*.Mask")
			(remove_unused_layers no)
			(net "P12V_PSU")
			(clearance -0.070866)
		)
		(pad "P5_6" thru_hole circle
			(at 2.54 21.59 270)
			(size 1.669796 1.669796)
			(drill 1.01981)
			(layers "*.Cu" "*.Mask")
			(remove_unused_layers no)
			(net "P12V_PSU")
			(clearance -0.070866)
		)
		(pad "P5_7" thru_hole circle
			(at 5.08 21.59 270)
			(size 1.669796 1.669796)
			(drill 1.01981)
			(layers "*.Cu" "*.Mask")
			(remove_unused_layers no)
			(net "P12V_PSU")
			(clearance -0.070866)
		)
		(pad "P5_8" thru_hole circle
			(at 7.62 21.59 270)
			(size 1.669796 1.669796)
			(drill 1.01981)
			(layers "*.Cu" "*.Mask")
			(remove_unused_layers no)
			(net "P12V_PSU")
			(clearance -0.070866)
		)
		(pad "P6_1" thru_hole circle
			(at 0 27.94 270)
			(size 1.669796 1.669796)
			(drill 1.01981)
			(layers "*.Cu" "*.Mask")
			(remove_unused_layers no)
			(net "P12V_PSU")
			(clearance -0.070866)
		)
		(pad "P6_2" thru_hole circle
			(at 2.54 27.94 270)
			(size 1.669796 1.669796)
			(drill 1.01981)
			(layers "*.Cu" "*.Mask")
			(remove_unused_layers no)
			(net "P12V_PSU")
			(clearance -0.070866)
		)
		(pad "P6_3" thru_hole circle
			(at 5.08 27.94 270)
			(size 1.669796 1.669796)
			(drill 1.01981)
			(layers "*.Cu" "*.Mask")
			(remove_unused_layers no)
			(net "P12V_PSU")
			(clearance -0.070866)
		)
		(pad "P6_4" thru_hole circle
			(at 7.62 27.94 270)
			(size 1.669796 1.669796)
			(drill 1.01981)
			(layers "*.Cu" "*.Mask")
			(remove_unused_layers no)
			(net "P12V_PSU")
			(clearance -0.070866)
		)
		(pad "P6_5" thru_hole circle
			(at 0 30.48 270)
			(size 1.669796 1.669796)
			(drill 1.01981)
			(layers "*.Cu" "*.Mask")
			(remove_unused_layers no)
			(net "P12V_PSU")
			(clearance -0.070866)
		)
		(pad "P6_6" thru_hole circle
			(at 2.54 30.48 270)
			(size 1.669796 1.669796)
			(drill 1.01981)
			(layers "*.Cu" "*.Mask")
			(remove_unused_layers no)
			(net "P12V_PSU")
			(clearance -0.070866)
		)
		(pad "P6_7" thru_hole circle
			(at 5.08 30.48 270)
			(size 1.669796 1.669796)
			(drill 1.01981)
			(layers "*.Cu" "*.Mask")
			(remove_unused_layers no)
			(net "P12V_PSU")
			(clearance -0.070866)
		)
		(pad "P6_8" thru_hole circle
			(at 7.62 30.48 270)
			(size 1.669796 1.669796)
			(drill 1.01981)
			(layers "*.Cu" "*.Mask")
			(remove_unused_layers no)
			(net "P12V_PSU")
			(clearance -0.070866)
		)
	)
)
